(kicad_pcb
	(version 20260206)
	(generator "pcbnew")
	(generator_version "10.0")
	(general
		(thickness 1.6)
		(legacy_teardrops no)
	)
	(paper "A4")
	(title_block
		(title "Wiwynn_Tioga_Pass_MB.brd")
		(comment 1 "Tioga Pass / footprints 541-548 of 4770")
	)
	(layers
		(0 "F.Cu" signal "TOP")
		(4 "In1.Cu" signal "L2GND")
		(6 "In2.Cu" signal "L3")
		(8 "In3.Cu" signal "L4GND")
		(10 "In4.Cu" signal "L5")
		(12 "In5.Cu" signal "L6GND")
		(14 "In6.Cu" signal "L7VCC")
		(16 "In7.Cu" signal "L8VCC")
		(18 "In8.Cu" signal "L9GND")
		(20 "In9.Cu" signal "L10")
		(22 "In10.Cu" signal "L11GND")
		(24 "In11.Cu" signal "L12")
		(26 "In12.Cu" signal "L13GND")
		(2 "B.Cu" signal "BOTTOM")
		(9 "F.Adhes" user "F.Adhesive")
		(11 "B.Adhes" user "B.Adhesive")
		(13 "F.Paste" user "Package Geometry/Pastemask Top")
		(15 "B.Paste" user "Package Geometry/Pastemask Bottom")
		(5 "F.SilkS" user "Ref Des/Silkscreen Top")
		(7 "B.SilkS" user "Ref Des/Silkscreen Bottom")
		(1 "F.Mask" user "Board Geometry/Soldermask Top")
		(3 "B.Mask" user "Board Geometry/Soldermask Bottom")
		(17 "Dwgs.User" user "User.Drawings")
		(19 "Cmts.User" user "User.Comments")
		(21 "Eco1.User" user "User.Eco1")
		(23 "Eco2.User" user "User.Eco2")
		(25 "Edge.Cuts" user "Board Geometry/Outline")
		(27 "Margin" user)
		(31 "F.CrtYd" user "Package Geometry/Place Bound Top")
		(29 "B.CrtYd" user "Package Geometry/Place Bound Bottom")
		(35 "F.Fab" user "Ref Des/Assembly Top")
		(33 "B.Fab" user "Ref Des/Assembly Bottom")
	)
	(footprint ""
		(layer "F.Cu")
		(at 370.967 -99.695)
		(property "Reference" "R7W9"
			(at -0.8382 -0.67818 0)
			(unlocked yes)
			(layer "F.SilkS")
			(effects
				(font
					(size 0.4064 0.254)
					(thickness 0.1524)
				)
				(justify left)
			)
		)
		(property "Value" ""
			(at 0 0 0)
			(layer "F.Fab")
			(effects
				(font
					(size 1.27 1.27)
				)
			)
		)
		(duplicate_pad_numbers_are_jumpers no)
		(fp_poly
			(pts
				(xy -0.2794 -0.1016) (xy 0.2794 -0.1016) (xy 0.2794 0.9906) (xy -0.2794 0.9906)
			)
			(stroke
				(width 0)
				(type default)
			)
			(fill no)
			(layer "F.CrtYd")
		)
		(fp_line
			(start -0.2794 -0.1016)
			(end -0.2794 0.9906)
			(stroke
				(width 0.1)
				(type default)
			)
			(layer "F.Fab")
		)
		(fp_line
			(start -0.2794 0.9906)
			(end 0.2794 0.9906)
			(stroke
				(width 0.1)
				(type default)
			)
			(layer "F.Fab")
		)
		(fp_line
			(start 0.2794 -0.1016)
			(end -0.2794 -0.1016)
			(stroke
				(width 0.1)
				(type default)
			)
			(layer "F.Fab")
		)
		(fp_line
			(start 0.2794 0.9906)
			(end 0.2794 -0.1016)
			(stroke
				(width 0.1)
				(type default)
			)
			(layer "F.Fab")
		)
		(pad "1" smd rect
			(at 0 0)
			(size 0.508 0.508)
			(layers "F.Cu" "F.Mask" "F.Paste")
			(net "FM_CPU0_RC_ERROR_N")
		)
		(pad "2" smd rect
			(at 0 0.889)
			(size 0.508 0.508)
			(layers "F.Cu" "F.Mask" "F.Paste")
			(net "FM_CPU0_RC_ERROR_R_N")
		)
		(zone
			(layer "F.Cu")
			(hatch none 0.5)
			(connect_pads
				(clearance 0)
			)
			(min_thickness 0.25)
			(keepout
				(tracks allowed)
				(vias not_allowed)
				(pads allowed)
				(copperpour not_allowed)
				(footprints allowed)
			)
			(placement
				(enabled no)
				(sheetname "")
			)
			(fill
				(thermal_gap 0.5)
				(thermal_bridge_width 0.5)
				(island_removal_mode 0)
			)
			(polygon
				(pts
					(xy 370.713 -99.441) (xy 371.221 -99.441) (xy 371.221 -99.06) (xy 370.713 -99.06)
				)
			)
		)
		(zone
			(layer "F.Cu")
			(hatch none 0.5)
			(connect_pads
				(clearance 0)
			)
			(min_thickness 0.25)
			(keepout
				(tracks not_allowed)
				(vias allowed)
				(pads allowed)
				(copperpour not_allowed)
				(footprints allowed)
			)
			(placement
				(enabled no)
				(sheetname "")
			)
			(fill
				(thermal_gap 0.5)
				(thermal_bridge_width 0.5)
				(island_removal_mode 0)
			)
			(polygon
				(pts
					(xy 370.713 -99.06) (xy 371.221 -99.06) (xy 371.221 -99.441) (xy 370.713 -99.441)
				)
			)
		)
	)
	(footprint ""
		(layer "F.Cu")
		(at 22.225 -71.6788 90)
		(property "Reference" "C1D21"
			(at 0 0 90)
			(layer "F.SilkS")
			(hide yes)
			(effects
				(font
					(size 1.27 1.27)
				)
			)
		)
		(property "Value" ""
			(at 0 0 90)
			(layer "F.Fab")
			(effects
				(font
					(size 1.27 1.27)
				)
			)
		)
		(duplicate_pad_numbers_are_jumpers no)
		(fp_poly
			(pts
				(xy 0.3048 -0.1016) (xy 0.3048 0.9906) (xy -0.3048 0.9906) (xy -0.3048 -0.1016)
			)
			(stroke
				(width 0)
				(type default)
			)
			(fill no)
			(layer "F.CrtYd")
		)
		(fp_line
			(start 0.3048 -0.1016)
			(end -0.3048 -0.1016)
			(stroke
				(width 0.1)
				(type default)
			)
			(layer "F.Fab")
		)
		(fp_line
			(start -0.3048 -0.1016)
			(end -0.3048 0.9906)
			(stroke
				(width 0.1)
				(type default)
			)
			(layer "F.Fab")
		)
		(fp_line
			(start 0.3048 0.9906)
			(end 0.3048 -0.1016)
			(stroke
				(width 0.1)
				(type default)
			)
			(layer "F.Fab")
		)
		(fp_line
			(start -0.3048 0.9906)
			(end 0.3048 0.9906)
			(stroke
				(width 0.1)
				(type default)
			)
			(layer "F.Fab")
		)
		(pad "1" smd rect
			(at 0 0 90)
			(size 0.508 0.508)
			(layers "F.Cu" "F.Mask" "F.Paste")
			(net "A_HSC_PSET")
		)
		(pad "2" smd rect
			(at 0 0.889 90)
			(size 0.508 0.508)
			(layers "F.Cu" "F.Mask" "F.Paste")
			(net "AGND_HSC")
		)
		(zone
			(layer "F.Cu")
			(hatch none 0.5)
			(connect_pads
				(clearance 0)
			)
			(min_thickness 0.25)
			(keepout
				(tracks allowed)
				(vias not_allowed)
				(pads allowed)
				(copperpour not_allowed)
				(footprints allowed)
			)
			(placement
				(enabled no)
				(sheetname "")
			)
			(fill
				(thermal_gap 0.5)
				(thermal_bridge_width 0.5)
				(island_removal_mode 0)
			)
			(polygon
				(pts
					(xy 22.479 -71.4248) (xy 22.479 -71.9328) (xy 22.86 -71.9328) (xy 22.86 -71.4248)
				)
			)
		)
		(zone
			(layer "F.Cu")
			(hatch none 0.5)
			(connect_pads
				(clearance 0)
			)
			(min_thickness 0.25)
			(keepout
				(tracks not_allowed)
				(vias allowed)
				(pads allowed)
				(copperpour not_allowed)
				(footprints allowed)
			)
			(placement
				(enabled no)
				(sheetname "")
			)
			(fill
				(thermal_gap 0.5)
				(thermal_bridge_width 0.5)
				(island_removal_mode 0)
			)
			(polygon
				(pts
					(xy 22.86 -71.4248) (xy 22.86 -71.9328) (xy 22.479 -71.9328) (xy 22.479 -71.4248)
				)
			)
		)
	)
	(footprint ""
		(layer "F.Cu")
		(at 173.5836 -104.4448 180)
		(property "Reference" "C4C3"
			(at 0 0 180)
			(layer "F.SilkS")
			(hide yes)
			(effects
				(font
					(size 1.27 1.27)
				)
			)
		)
		(property "Value" ""
			(at 0 0 180)
			(layer "F.Fab")
			(effects
				(font
					(size 1.27 1.27)
				)
			)
		)
		(duplicate_pad_numbers_are_jumpers no)
		(fp_poly
			(pts
				(xy 0.3048 -0.1016) (xy 0.3048 0.9906) (xy -0.3048 0.9906) (xy -0.3048 -0.1016)
			)
			(stroke
				(width 0)
				(type default)
			)
			(fill no)
			(layer "F.CrtYd")
		)
		(fp_line
			(start 0.3048 0.9906)
			(end 0.3048 -0.1016)
			(stroke
				(width 0.1)
				(type default)
			)
			(layer "F.Fab")
		)
		(fp_line
			(start 0.3048 -0.1016)
			(end -0.3048 -0.1016)
			(stroke
				(width 0.1)
				(type default)
			)
			(layer "F.Fab")
		)
		(fp_line
			(start -0.3048 0.9906)
			(end 0.3048 0.9906)
			(stroke
				(width 0.1)
				(type default)
			)
			(layer "F.Fab")
		)
		(fp_line
			(start -0.3048 -0.1016)
			(end -0.3048 0.9906)
			(stroke
				(width 0.1)
				(type default)
			)
			(layer "F.Fab")
		)
		(pad "1" smd rect
			(at 0 0 180)
			(size 0.508 0.508)
			(layers "F.Cu" "F.Mask" "F.Paste")
			(net "P3V3_STBY")
		)
		(pad "2" smd rect
			(at 0 0.889 180)
			(size 0.508 0.508)
			(layers "F.Cu" "F.Mask" "F.Paste")
			(net "GND")
		)
		(zone
			(layer "F.Cu")
			(hatch none 0.5)
			(connect_pads
				(clearance 0)
			)
			(min_thickness 0.25)
			(keepout
				(tracks not_allowed)
				(vias allowed)
				(pads allowed)
				(copperpour not_allowed)
				(footprints allowed)
			)
			(placement
				(enabled no)
				(sheetname "")
			)
			(fill
				(thermal_gap 0.5)
				(thermal_bridge_width 0.5)
				(island_removal_mode 0)
			)
			(polygon
				(pts
					(xy 173.8376 -105.0798) (xy 173.3296 -105.0798) (xy 173.3296 -104.6988) (xy 173.8376 -104.6988)
				)
			)
		)
		(zone
			(layer "F.Cu")
			(hatch none 0.5)
			(connect_pads
				(clearance 0)
			)
			(min_thickness 0.25)
			(keepout
				(tracks allowed)
				(vias not_allowed)
				(pads allowed)
				(copperpour not_allowed)
				(footprints allowed)
			)
			(placement
				(enabled no)
				(sheetname "")
			)
			(fill
				(thermal_gap 0.5)
				(thermal_bridge_width 0.5)
				(island_removal_mode 0)
			)
			(polygon
				(pts
					(xy 173.8376 -104.6988) (xy 173.3296 -104.6988) (xy 173.3296 -105.0798) (xy 173.8376 -105.0798)
				)
			)
		)
	)
	(footprint ""
		(layer "F.Cu")
		(at 408.7495 -113.284 -90)
		(property "Reference" "R8B30"
			(at 0 0 270)
			(layer "F.SilkS")
			(hide yes)
			(effects
				(font
					(size 1.27 1.27)
				)
			)
		)
		(property "Value" ""
			(at 0 0 270)
			(layer "F.Fab")
			(effects
				(font
					(size 1.27 1.27)
				)
			)
		)
		(duplicate_pad_numbers_are_jumpers no)
		(fp_poly
			(pts
				(xy -0.2794 -0.1016) (xy 0.2794 -0.1016) (xy 0.2794 0.9906) (xy -0.2794 0.9906)
			)
			(stroke
				(width 0)
				(type default)
			)
			(fill no)
			(layer "F.CrtYd")
		)
		(fp_line
			(start -0.2794 0.9906)
			(end 0.2794 0.9906)
			(stroke
				(width 0.1)
				(type default)
			)
			(layer "F.Fab")
		)
		(fp_line
			(start 0.2794 0.9906)
			(end 0.2794 -0.1016)
			(stroke
				(width 0.1)
				(type default)
			)
			(layer "F.Fab")
		)
		(fp_line
			(start -0.2794 -0.1016)
			(end -0.2794 0.9906)
			(stroke
				(width 0.1)
				(type default)
			)
			(layer "F.Fab")
		)
		(fp_line
			(start 0.2794 -0.1016)
			(end -0.2794 -0.1016)
			(stroke
				(width 0.1)
				(type default)
			)
			(layer "F.Fab")
		)
		(pad "1" smd rect
			(at 0 0 270)
			(size 0.508 0.508)
			(layers "F.Cu" "F.Mask" "F.Paste")
			(net "P3V3_STBY")
		)
		(pad "2" smd rect
			(at 0 0.889 270)
			(size 0.508 0.508)
			(layers "F.Cu" "F.Mask" "F.Paste")
			(net "FM_XRC_READY_N")
		)
		(zone
			(layer "F.Cu")
			(hatch none 0.5)
			(connect_pads
				(clearance 0)
			)
			(min_thickness 0.25)
			(keepout
				(tracks not_allowed)
				(vias allowed)
				(pads allowed)
				(copperpour not_allowed)
				(footprints allowed)
			)
			(placement
				(enabled no)
				(sheetname "")
			)
			(fill
				(thermal_gap 0.5)
				(thermal_bridge_width 0.5)
				(island_removal_mode 0)
			)
			(polygon
				(pts
					(xy 408.1145 -113.538) (xy 408.1145 -113.03) (xy 408.4955 -113.03) (xy 408.4955 -113.538)
				)
			)
		)
		(zone
			(layer "F.Cu")
			(hatch none 0.5)
			(connect_pads
				(clearance 0)
			)
			(min_thickness 0.25)
			(keepout
				(tracks allowed)
				(vias not_allowed)
				(pads allowed)
				(copperpour not_allowed)
				(footprints allowed)
			)
			(placement
				(enabled no)
				(sheetname "")
			)
			(fill
				(thermal_gap 0.5)
				(thermal_bridge_width 0.5)
				(island_removal_mode 0)
			)
			(polygon
				(pts
					(xy 408.4955 -113.538) (xy 408.4955 -113.03) (xy 408.1145 -113.03) (xy 408.1145 -113.538)
				)
			)
		)
	)
	(footprint ""
		(layer "F.Cu")
		(at 486.687876 -27.227784)
		(property "Reference" "R9F68"
			(at 0 0 0)
			(layer "F.SilkS")
			(hide yes)
			(effects
				(font
					(size 1.27 1.27)
				)
			)
		)
		(property "Value" ""
			(at 0 0 0)
			(layer "F.Fab")
			(effects
				(font
					(size 1.27 1.27)
				)
			)
		)
		(duplicate_pad_numbers_are_jumpers no)
		(fp_poly
			(pts
				(xy -0.2794 -0.1016) (xy 0.2794 -0.1016) (xy 0.2794 0.9906) (xy -0.2794 0.9906)
			)
			(stroke
				(width 0)
				(type default)
			)
			(fill no)
			(layer "F.CrtYd")
		)
		(fp_line
			(start -0.2794 -0.1016)
			(end -0.2794 0.9906)
			(stroke
				(width 0.1)
				(type default)
			)
			(layer "F.Fab")
		)
		(fp_line
			(start -0.2794 0.9906)
			(end 0.2794 0.9906)
			(stroke
				(width 0.1)
				(type default)
			)
			(layer "F.Fab")
		)
		(fp_line
			(start 0.2794 -0.1016)
			(end -0.2794 -0.1016)
			(stroke
				(width 0.1)
				(type default)
			)
			(layer "F.Fab")
		)
		(fp_line
			(start 0.2794 0.9906)
			(end 0.2794 -0.1016)
			(stroke
				(width 0.1)
				(type default)
			)
			(layer "F.Fab")
		)
		(pad "1" smd rect
			(at 0 0)
			(size 0.508 0.508)
			(layers "F.Cu" "F.Mask" "F.Paste")
			(net "SP2_BMC_CM_UART_RX_R")
		)
		(pad "2" smd rect
			(at 0 0.889)
			(size 0.508 0.508)
			(layers "F.Cu" "F.Mask" "F.Paste")
			(net "SP2_BMC_CM_UART_RX")
		)
		(zone
			(layer "F.Cu")
			(hatch none 0.5)
			(connect_pads
				(clearance 0)
			)
			(min_thickness 0.25)
			(keepout
				(tracks allowed)
				(vias not_allowed)
				(pads allowed)
				(copperpour not_allowed)
				(footprints allowed)
			)
			(placement
				(enabled no)
				(sheetname "")
			)
			(fill
				(thermal_gap 0.5)
				(thermal_bridge_width 0.5)
				(island_removal_mode 0)
			)
			(polygon
				(pts
					(xy 486.433876 -26.973784) (xy 486.941876 -26.973784) (xy 486.941876 -26.592784) (xy 486.433876 -26.592784)
				)
			)
		)
		(zone
			(layer "F.Cu")
			(hatch none 0.5)
			(connect_pads
				(clearance 0)
			)
			(min_thickness 0.25)
			(keepout
				(tracks not_allowed)
				(vias allowed)
				(pads allowed)
				(copperpour not_allowed)
				(footprints allowed)
			)
			(placement
				(enabled no)
				(sheetname "")
			)
			(fill
				(thermal_gap 0.5)
				(thermal_bridge_width 0.5)
				(island_removal_mode 0)
			)
			(polygon
				(pts
					(xy 486.433876 -26.592784) (xy 486.941876 -26.592784) (xy 486.941876 -26.973784) (xy 486.433876 -26.973784)
				)
			)
		)
	)
	(footprint ""
		(layer "F.Cu")
		(at 198.065644 -77.513942 90)
		(property "Reference" "C4D5"
			(at -0.8382 -0.67818 90)
			(unlocked yes)
			(layer "F.SilkS")
			(effects
				(font
					(size 0.4064 0.254)
					(thickness 0.1524)
				)
				(justify left)
			)
		)
		(property "Value" ""
			(at 0 0 90)
			(layer "F.Fab")
			(effects
				(font
					(size 1.27 1.27)
				)
			)
		)
		(duplicate_pad_numbers_are_jumpers no)
		(fp_poly
			(pts
				(xy 0.3048 -0.1016) (xy 0.3048 0.9906) (xy -0.3048 0.9906) (xy -0.3048 -0.1016)
			)
			(stroke
				(width 0)
				(type default)
			)
			(fill no)
			(layer "F.CrtYd")
		)
		(fp_line
			(start 0.3048 -0.1016)
			(end -0.3048 -0.1016)
			(stroke
				(width 0.1)
				(type default)
			)
			(layer "F.Fab")
		)
		(fp_line
			(start -0.3048 -0.1016)
			(end -0.3048 0.9906)
			(stroke
				(width 0.1)
				(type default)
			)
			(layer "F.Fab")
		)
		(fp_line
			(start 0.3048 0.9906)
			(end 0.3048 -0.1016)
			(stroke
				(width 0.1)
				(type default)
			)
			(layer "F.Fab")
		)
		(fp_line
			(start -0.3048 0.9906)
			(end 0.3048 0.9906)
			(stroke
				(width 0.1)
				(type default)
			)
			(layer "F.Fab")
		)
		(pad "1" smd rect
			(at 0 0 90)
			(size 0.508 0.508)
			(layers "F.Cu" "F.Mask" "F.Paste")
			(net "P5V_STBY")
		)
		(pad "2" smd rect
			(at 0 0.889 90)
			(size 0.508 0.508)
			(layers "F.Cu" "F.Mask" "F.Paste")
			(net "GND")
		)
		(zone
			(layer "F.Cu")
			(hatch none 0.5)
			(connect_pads
				(clearance 0)
			)
			(min_thickness 0.25)
			(keepout
				(tracks allowed)
				(vias not_allowed)
				(pads allowed)
				(copperpour not_allowed)
				(footprints allowed)
			)
			(placement
				(enabled no)
				(sheetname "")
			)
			(fill
				(thermal_gap 0.5)
				(thermal_bridge_width 0.5)
				(island_removal_mode 0)
			)
			(polygon
				(pts
					(xy 198.319644 -77.259942) (xy 198.319644 -77.767942) (xy 198.700644 -77.767942) (xy 198.700644 -77.259942)
				)
			)
		)
		(zone
			(layer "F.Cu")
			(hatch none 0.5)
			(connect_pads
				(clearance 0)
			)
			(min_thickness 0.25)
			(keepout
				(tracks not_allowed)
				(vias allowed)
				(pads allowed)
				(copperpour not_allowed)
				(footprints allowed)
			)
			(placement
				(enabled no)
				(sheetname "")
			)
			(fill
				(thermal_gap 0.5)
				(thermal_bridge_width 0.5)
				(island_removal_mode 0)
			)
			(polygon
				(pts
					(xy 198.700644 -77.259942) (xy 198.700644 -77.767942) (xy 198.319644 -77.767942) (xy 198.319644 -77.259942)
				)
			)
		)
	)
	(footprint ""
		(layer "F.Cu")
		(at 166.497 -73.66 180)
		(property "Reference" "R4D40"
			(at 0 0 180)
			(layer "F.SilkS")
			(hide yes)
			(effects
				(font
					(size 1.27 1.27)
				)
			)
		)
		(property "Value" ""
			(at 0 0 180)
			(layer "F.Fab")
			(effects
				(font
					(size 1.27 1.27)
				)
			)
		)
		(duplicate_pad_numbers_are_jumpers no)
		(fp_poly
			(pts
				(xy -0.2794 -0.1016) (xy 0.2794 -0.1016) (xy 0.2794 0.9906) (xy -0.2794 0.9906)
			)
			(stroke
				(width 0)
				(type default)
			)
			(fill no)
			(layer "F.CrtYd")
		)
		(fp_line
			(start 0.2794 0.9906)
			(end 0.2794 -0.1016)
			(stroke
				(width 0.1)
				(type default)
			)
			(layer "F.Fab")
		)
		(fp_line
			(start 0.2794 -0.1016)
			(end -0.2794 -0.1016)
			(stroke
				(width 0.1)
				(type default)
			)
			(layer "F.Fab")
		)
		(fp_line
			(start -0.2794 0.9906)
			(end 0.2794 0.9906)
			(stroke
				(width 0.1)
				(type default)
			)
			(layer "F.Fab")
		)
		(fp_line
			(start -0.2794 -0.1016)
			(end -0.2794 0.9906)
			(stroke
				(width 0.1)
				(type default)
			)
			(layer "F.Fab")
		)
		(pad "1" smd rect
			(at 0 0 180)
			(size 0.508 0.508)
			(layers "F.Cu" "F.Mask" "F.Paste")
			(net "P3V3_DB1200")
		)
		(pad "2" smd rect
			(at 0 0.889 180)
			(size 0.508 0.508)
			(layers "F.Cu" "F.Mask" "F.Paste")
			(net "FM_100M_N")
		)
		(zone
			(layer "F.Cu")
			(hatch none 0.5)
			(connect_pads
				(clearance 0)
			)
			(min_thickness 0.25)
			(keepout
				(tracks not_allowed)
				(vias allowed)
				(pads allowed)
				(copperpour not_allowed)
				(footprints allowed)
			)
			(placement
				(enabled no)
				(sheetname "")
			)
			(fill
				(thermal_gap 0.5)
				(thermal_bridge_width 0.5)
				(island_removal_mode 0)
			)
			(polygon
				(pts
					(xy 166.751 -74.295) (xy 166.243 -74.295) (xy 166.243 -73.914) (xy 166.751 -73.914)
				)
			)
		)
		(zone
			(layer "F.Cu")
			(hatch none 0.5)
			(connect_pads
				(clearance 0)
			)
			(min_thickness 0.25)
			(keepout
				(tracks allowed)
				(vias not_allowed)
				(pads allowed)
				(copperpour not_allowed)
				(footprints allowed)
			)
			(placement
				(enabled no)
				(sheetname "")
			)
			(fill
				(thermal_gap 0.5)
				(thermal_bridge_width 0.5)
				(island_removal_mode 0)
			)
			(polygon
				(pts
					(xy 166.751 -73.914) (xy 166.243 -73.914) (xy 166.243 -74.295) (xy 166.751 -74.295)
				)
			)
		)
	)
	(footprint ""
		(layer "F.Cu")
		(at 365.76 -130.302)
		(property "Reference" ""
			(at 0 0 0)
			(layer "F.SilkS")
			(hide yes)
			(effects
				(font
					(size 1.27 1.27)
				)
			)
		)
		(property "Value" ""
			(at 0 0 0)
			(layer "F.Fab")
			(effects
				(font
					(size 1.27 1.27)
				)
			)
		)
		(duplicate_pad_numbers_are_jumpers no)
		(fp_poly
			(pts
				(arc
					(start 2.032 0)
					(mid -2.032 0)
					(end 2.032 0)
				)
			)
			(stroke
				(width 0)
				(type default)
			)
			(fill no)
			(layer "F.CrtYd")
		)
		(pad "1" smd circle
			(at 0 0)
			(size 1.016 1.016)
			(layers "F.Cu" "F.Mask" "F.Paste")
			(net "Net_132")
		)
		(zone
			(layer "F.Cu")
			(hatch none 0.5)
			(connect_pads
				(clearance 0)
			)
			(min_thickness 0.25)
			(keepout
				(tracks not_allowed)
				(vias allowed)
				(pads allowed)
				(copperpour not_allowed)
				(footprints allowed)
			)
			(placement
				(enabled no)
				(sheetname "")
			)
			(fill
				(thermal_gap 0.5)
				(thermal_bridge_width 0.5)
				(island_removal_mode 0)
			)
			(polygon
				(pts
					(arc
						(start 367.284 -130.302)
						(mid 364.236 -130.302)
						(end 367.284 -130.302)
					)
				)
			)
		)
		(zone
			(layers "F.Cu" "B.Cu" "In1.Cu" "In2.Cu" "In3.Cu" "In4.Cu" "In5.Cu" "In6.Cu"
				"In7.Cu" "In8.Cu" "In9.Cu" "In10.Cu" "In11.Cu" "In12.Cu"
			)
			(hatch none 0.5)
			(connect_pads
				(clearance 0)
			)
			(min_thickness 0.25)
			(keepout
				(tracks allowed)
				(vias not_allowed)
				(pads allowed)
				(copperpour not_allowed)
				(footprints allowed)
			)
			(placement
				(enabled no)
				(sheetname "")
			)
			(fill
				(thermal_gap 0.5)
				(thermal_bridge_width 0.5)
				(island_removal_mode 0)
			)
			(polygon
				(pts
					(arc
						(start 367.284 -130.302)
						(mid 364.236 -130.302)
						(end 367.284 -130.302)
					)
				)
			)
		)
	)
)
